# S9S_MB_2U (Grand Teton) — schematic netlist excerpt (pin names and nets, part order shuffled) for the footprints in the layout excerpt that follows; sources: Cadence DE-HDL packaged netlist, KiCad conversion of 03242023_DA0F0TMBIJ0_F0T_Motherboard_J_brd_V01_OCP.brd

R4456  Q_RES  10K 1% EMPTY  pkg 0402LF  page 196 : A = P3V3_AUX ; B = USB_HUB_2_OVCUR1
R2488  Q_RES  4.7K 1% CHIP  pkg 0402LF  page 155 : A = P3V3_AUX ; B = OCP_SFF_WAKE_BUFF_N

(kicad_pcb
	(version 20260206)
	(generator "pcbnew")
	(generator_version "10.0")
	(general
		(thickness 1.6)
		(legacy_teardrops no)
	)
	(paper "A4")
	(title_block
		(title "03242023_DA0F0TMBIJ0_F0T_Motherboard_J_brd_V01_OCP.brd")
		(comment 1 "Grand Teton / footprints 2565-2566 of 6105")
	)
	(layers
		(0 "F.Cu" signal "TOP")
		(4 "In1.Cu" signal "GND")
		(6 "In2.Cu" signal "IN1")
		(8 "In3.Cu" signal "GND1")
		(10 "In4.Cu" signal "IN2")
		(12 "In5.Cu" signal "GND2")
		(14 "In6.Cu" signal "IN3")
		(16 "In7.Cu" signal "GND3")
		(18 "In8.Cu" signal "VCC")
		(20 "In9.Cu" signal "VCC1")
		(22 "In10.Cu" signal "GND4")
		(24 "In11.Cu" signal "IN4")
		(26 "In12.Cu" signal "GND5")
		(28 "In13.Cu" signal "IN5")
		(30 "In14.Cu" signal "GND6")
		(32 "In15.Cu" signal "IN6")
		(34 "In16.Cu" signal "GND7")
		(2 "B.Cu" signal "BOTTOM")
		(9 "F.Adhes" user "F.Adhesive")
		(11 "B.Adhes" user "B.Adhesive")
		(13 "F.Paste" user "Package Geometry/Pastemask Top")
		(15 "B.Paste" user "Package Geometry/Pastemask Bottom")
		(5 "F.SilkS" user "Ref Des/Silkscreen Top")
		(7 "B.SilkS" user "Ref Des/Silkscreen Bottom")
		(1 "F.Mask" user "Board Geometry/Soldermask Top")
		(3 "B.Mask" user "Board Geometry/Soldermask Bottom")
		(17 "Dwgs.User" user "User.Drawings")
		(19 "Cmts.User" user "User.Comments")
		(21 "Eco1.User" user "User.Eco1")
		(23 "Eco2.User" user "User.Eco2")
		(25 "Edge.Cuts" user "Board Geometry/Outline")
		(27 "Margin" user)
		(31 "F.CrtYd" user "Package Geometry/Place Bound Top")
		(29 "B.CrtYd" user "Package Geometry/Place Bound Bottom")
		(35 "F.Fab" user "Ref Des/Assembly Top")
		(33 "B.Fab" user "Ref Des/Assembly Bottom")
	)
	(footprint ""
		(layer "F.Cu")
		(at 468.49284 -43.735498 180)
		(property "Reference" "R2488"
			(at 0 0 180)
			(layer "F.SilkS")
			(hide yes)
			(effects
				(font
					(size 1.27 1.27)
				)
			)
		)
		(property "Value" ""
			(at 0 0 180)
			(layer "F.Fab")
			(effects
				(font
					(size 1.27 1.27)
				)
			)
		)
		(duplicate_pad_numbers_are_jumpers no)
		(fp_line
			(start 0.7874 0.4064)
			(end -0.7874 0.4064)
			(stroke
				(width 0.1524)
				(type default)
			)
			(layer "F.SilkS")
		)
		(fp_line
			(start 0.7874 -0.4064)
			(end 0.7874 0.4064)
			(stroke
				(width 0.1524)
				(type default)
			)
			(layer "F.SilkS")
		)
		(fp_line
			(start -0.7874 0.4064)
			(end -0.7874 -0.4064)
			(stroke
				(width 0.1524)
				(type default)
			)
			(layer "F.SilkS")
		)
		(fp_line
			(start -0.7874 -0.4064)
			(end 0.7874 -0.4064)
			(stroke
				(width 0.1524)
				(type default)
			)
			(layer "F.SilkS")
		)
		(fp_line
			(start 0.67945 0.3048)
			(end 0.120396 0.3048)
			(stroke
				(width 0.1)
				(type default)
			)
			(layer "F.Fab")
		)
		(fp_line
			(start 0.67945 -0.3048)
			(end 0.67945 0.3048)
			(stroke
				(width 0.1)
				(type default)
			)
			(layer "F.Fab")
		)
		(fp_line
			(start 0.12065 -0.2794)
			(end 0.12065 -0.3048)
			(stroke
				(width 0.1)
				(type default)
			)
			(layer "F.Fab")
		)
		(fp_line
			(start 0.12065 -0.3048)
			(end 0.67945 -0.3048)
			(stroke
				(width 0.1)
				(type default)
			)
			(layer "F.Fab")
		)
		(fp_line
			(start 0.120396 0.3048)
			(end 0.120396 0.2794)
			(stroke
				(width 0.1)
				(type default)
			)
			(layer "F.Fab")
		)
		(fp_line
			(start 0.120396 0.2794)
			(end -0.12065 0.2794)
			(stroke
				(width 0.1)
				(type default)
			)
			(layer "F.Fab")
		)
		(fp_line
			(start -0.12065 0.3048)
			(end -0.67945 0.3048)
			(stroke
				(width 0.1)
				(type default)
			)
			(layer "F.Fab")
		)
		(fp_line
			(start -0.12065 0.2794)
			(end -0.12065 0.3048)
			(stroke
				(width 0.1)
				(type default)
			)
			(layer "F.Fab")
		)
		(fp_line
			(start -0.12065 -0.2794)
			(end 0.12065 -0.2794)
			(stroke
				(width 0.1)
				(type default)
			)
			(layer "F.Fab")
		)
		(fp_line
			(start -0.12065 -0.305054)
			(end -0.12065 -0.2794)
			(stroke
				(width 0.1)
				(type default)
			)
			(layer "F.Fab")
		)
		(fp_line
			(start -0.67945 0.3048)
			(end -0.67945 -0.305054)
			(stroke
				(width 0.1)
				(type default)
			)
			(layer "F.Fab")
		)
		(fp_line
			(start -0.67945 -0.305054)
			(end -0.12065 -0.305054)
			(stroke
				(width 0.1)
				(type default)
			)
			(layer "F.Fab")
		)
		(pad "1" smd circle
			(at -0.40005 0 180)
			(size 0 0)
			(layers "F.Cu" "F.Mask" "F.Paste")
			(net "P3V3_AUX")
		)
		(pad "2" smd circle
			(at 0.40005 0 180)
			(size 0 0)
			(layers "F.Cu" "F.Mask" "F.Paste")
			(net "OCP_SFF_WAKE_BUFF_N")
		)
	)
	(footprint ""
		(layer "F.Cu")
		(at 164.247576 -39.20363 180)
		(property "Reference" "R4456"
			(at 0 0 180)
			(layer "F.SilkS")
			(hide yes)
			(effects
				(font
					(size 1.27 1.27)
				)
			)
		)
		(property "Value" ""
			(at 0 0 180)
			(layer "F.Fab")
			(effects
				(font
					(size 1.27 1.27)
				)
			)
		)
		(duplicate_pad_numbers_are_jumpers no)
		(fp_line
			(start 0.7874 0.4064)
			(end -0.7874 0.4064)
			(stroke
				(width 0.1524)
				(type default)
			)
			(layer "F.SilkS")
		)
		(fp_line
			(start 0.7874 -0.4064)
			(end 0.7874 0.4064)
			(stroke
				(width 0.1524)
				(type default)
			)
			(layer "F.SilkS")
		)
		(fp_line
			(start -0.7874 0.4064)
			(end -0.7874 -0.4064)
			(stroke
				(width 0.1524)
				(type default)
			)
			(layer "F.SilkS")
		)
		(fp_line
			(start -0.7874 -0.4064)
			(end 0.7874 -0.4064)
			(stroke
				(width 0.1524)
				(type default)
			)
			(layer "F.SilkS")
		)
		(fp_line
			(start 0.67945 0.3048)
			(end 0.120396 0.3048)
			(stroke
				(width 0.1)
				(type default)
			)
			(layer "F.Fab")
		)
		(fp_line
			(start 0.67945 -0.3048)
			(end 0.67945 0.3048)
			(stroke
				(width 0.1)
				(type default)
			)
			(layer "F.Fab")
		)
		(fp_line
			(start 0.12065 -0.2794)
			(end 0.12065 -0.3048)
			(stroke
				(width 0.1)
				(type default)
			)
			(layer "F.Fab")
		)
		(fp_line
			(start 0.12065 -0.3048)
			(end 0.67945 -0.3048)
			(stroke
				(width 0.1)
				(type default)
			)
			(layer "F.Fab")
		)
		(fp_line
			(start 0.120396 0.3048)
			(end 0.120396 0.2794)
			(stroke
				(width 0.1)
				(type default)
			)
			(layer "F.Fab")
		)
		(fp_line
			(start 0.120396 0.2794)
			(end -0.12065 0.2794)
			(stroke
				(width 0.1)
				(type default)
			)
			(layer "F.Fab")
		)
		(fp_line
			(start -0.12065 0.3048)
			(end -0.67945 0.3048)
			(stroke
				(width 0.1)
				(type default)
			)
			(layer "F.Fab")
		)
		(fp_line
			(start -0.12065 0.2794)
			(end -0.12065 0.3048)
			(stroke
				(width 0.1)
				(type default)
			)
			(layer "F.Fab")
		)
		(fp_line
			(start -0.12065 -0.2794)
			(end 0.12065 -0.2794)
			(stroke
				(width 0.1)
				(type default)
			)
			(layer "F.Fab")
		)
		(fp_line
			(start -0.12065 -0.305054)
			(end -0.12065 -0.2794)
			(stroke
				(width 0.1)
				(type default)
			)
			(layer "F.Fab")
		)
		(fp_line
			(start -0.67945 0.3048)
			(end -0.67945 -0.305054)
			(stroke
				(width 0.1)
				(type default)
			)
			(layer "F.Fab")
		)
		(fp_line
			(start -0.67945 -0.305054)
			(end -0.12065 -0.305054)
			(stroke
				(width 0.1)
				(type default)
			)
			(layer "F.Fab")
		)
		(pad "1" smd circle
			(at -0.40005 0 180)
			(size 0 0)
			(layers "F.Cu" "F.Mask" "F.Paste")
			(net "P3V3_AUX")
		)
		(pad "2" smd circle
			(at 0.40005 0 180)
			(size 0 0)
			(layers "F.Cu" "F.Mask" "F.Paste")
			(net "USB_HUB_2_OVCUR1")
		)
	)
)
